(kicad_sch (version 20230121) (generator eeschema)

  (paper "A3")

  (title_block
    (title "Kria K26 Devboard")
    (date "2024-03-26")
    (rev "1.2.5")
    (comment 1 "www.antmicro.com")
    (comment 2 "Antmicro Ltd.")
  )

  (junction (at 184.785 110.49) (diameter 0) (color 0 0 0 0)
  )
  (junction (at 234.315 95.25) (diameter 0) (color 0 0 0 0)
  )
  (junction (at 249.555 106.045) (diameter 0) (color 0 0 0 0)
  )
  (junction (at 226.06 85.725) (diameter 0) (color 0 0 0 0)
  )
  (junction (at 226.06 95.25) (diameter 0) (color 0 0 0 0)
  )
  (junction (at 137.16 110.49) (diameter 0) (color 0 0 0 0)
  )
  (junction (at 267.97 106.045) (diameter 0) (color 0 0 0 0)
  )
  (junction (at 217.805 182.88) (diameter 0) (color 0 0 0 0)
  )
  (junction (at 256.54 106.045) (diameter 0) (color 0 0 0 0)
  )
  (junction (at 237.49 168.275) (diameter 0) (color 0 0 0 0)
  )
  (junction (at 234.315 85.725) (diameter 0) (color 0 0 0 0)
  )

  (no_connect (at 177.165 170.18))

  (bus_entry (at 140.335 147.32) (size 2.54 2.54)
    (stroke (width 0) (type default))
  )
  (bus_entry (at 140.335 157.48) (size 2.54 2.54)
    (stroke (width 0) (type default))
  )
  (bus_entry (at 140.335 180.34) (size 2.54 2.54)
    (stroke (width 0) (type default))
  )
  (bus_entry (at 140.335 149.86) (size 2.54 2.54)
    (stroke (width 0) (type default))
  )
  (bus_entry (at 140.335 154.94) (size 2.54 2.54)
    (stroke (width 0) (type default))
  )
  (bus_entry (at 140.335 160.02) (size 2.54 2.54)
    (stroke (width 0) (type default))
  )
  (bus_entry (at 140.335 162.56) (size 2.54 2.54)
    (stroke (width 0) (type default))
  )

  (wire (pts (xy 196.215 165.1) (xy 205.105 165.1))
    (stroke (width 0) (type default))
  )
  (wire (pts (xy 196.215 157.48) (xy 205.105 157.48))
    (stroke (width 0) (type default))
  )
  (bus (pts (xy 140.335 157.48) (xy 140.335 160.02))
    (stroke (width 0) (type default))
  )

  (wire (pts (xy 198.12 189.23) (xy 192.405 189.23))
    (stroke (width 0) (type default))
  )
  (wire (pts (xy 249.555 106.045) (xy 249.555 104.14))
    (stroke (width 0) (type default))
  )
  (wire (pts (xy 217.805 175.895) (xy 217.805 173.99))
    (stroke (width 0) (type default))
  )
  (wire (pts (xy 226.06 85.725) (xy 226.06 88.265))
    (stroke (width 0) (type default))
  )
  (wire (pts (xy 196.215 149.86) (xy 205.105 149.86))
    (stroke (width 0) (type default))
  )
  (bus (pts (xy 140.335 154.94) (xy 140.335 157.48))
    (stroke (width 0) (type default))
  )

  (wire (pts (xy 135.89 110.49) (xy 137.16 110.49))
    (stroke (width 0) (type default))
  )
  (wire (pts (xy 158.115 81.28) (xy 158.115 83.185))
    (stroke (width 0) (type default))
  )
  (wire (pts (xy 234.315 93.345) (xy 234.315 95.25))
    (stroke (width 0) (type default))
  )
  (wire (pts (xy 196.215 160.02) (xy 205.105 160.02))
    (stroke (width 0) (type default))
  )
  (bus (pts (xy 140.335 143.51) (xy 140.335 147.32))
    (stroke (width 0) (type default))
  )

  (wire (pts (xy 249.555 85.725) (xy 249.555 91.44))
    (stroke (width 0) (type default))
  )
  (wire (pts (xy 155.575 81.28) (xy 158.115 81.28))
    (stroke (width 0) (type default))
  )
  (wire (pts (xy 142.875 160.02) (xy 160.655 160.02))
    (stroke (width 0) (type default))
  )
  (wire (pts (xy 137.16 110.49) (xy 137.16 115.57))
    (stroke (width 0) (type default))
  )
  (wire (pts (xy 184.785 110.49) (xy 184.785 108.585))
    (stroke (width 0) (type default))
  )
  (wire (pts (xy 172.085 116.84) (xy 172.085 115.57))
    (stroke (width 0) (type default))
  )
  (wire (pts (xy 137.16 115.57) (xy 152.4 115.57))
    (stroke (width 0) (type default))
  )
  (wire (pts (xy 267.97 106.045) (xy 256.54 106.045))
    (stroke (width 0) (type default))
  )
  (bus (pts (xy 133.985 143.51) (xy 140.335 143.51))
    (stroke (width 0) (type default))
  )

  (wire (pts (xy 142.875 182.88) (xy 217.805 182.88))
    (stroke (width 0) (type default))
  )
  (wire (pts (xy 142.875 157.48) (xy 160.655 157.48))
    (stroke (width 0) (type default))
  )
  (wire (pts (xy 176.53 189.23) (xy 179.07 189.23))
    (stroke (width 0) (type default))
  )
  (wire (pts (xy 139.7 81.28) (xy 139.7 83.185))
    (stroke (width 0) (type default))
  )
  (wire (pts (xy 234.315 85.725) (xy 226.06 85.725))
    (stroke (width 0) (type default))
  )
  (wire (pts (xy 226.695 163.195) (xy 239.395 163.195))
    (stroke (width 0) (type default))
  )
  (wire (pts (xy 196.215 162.56) (xy 205.105 162.56))
    (stroke (width 0) (type default))
  )
  (wire (pts (xy 226.695 145.415) (xy 239.395 145.415))
    (stroke (width 0) (type default))
  )
  (wire (pts (xy 174.625 83.185) (xy 174.625 81.28))
    (stroke (width 0) (type default))
  )
  (wire (pts (xy 173.355 144.78) (xy 177.165 144.78))
    (stroke (width 0) (type default))
  )
  (wire (pts (xy 182.88 101.6) (xy 184.785 101.6))
    (stroke (width 0) (type default))
  )
  (wire (pts (xy 267.97 106.045) (xy 276.86 106.045))
    (stroke (width 0) (type default))
  )
  (wire (pts (xy 170.18 110.49) (xy 184.785 110.49))
    (stroke (width 0) (type default))
  )
  (wire (pts (xy 226.06 95.25) (xy 234.315 95.25))
    (stroke (width 0) (type default))
  )
  (wire (pts (xy 168.275 149.86) (xy 177.165 149.86))
    (stroke (width 0) (type default))
  )
  (wire (pts (xy 170.815 162.56) (xy 177.165 162.56))
    (stroke (width 0) (type default))
  )
  (wire (pts (xy 184.785 110.49) (xy 186.69 110.49))
    (stroke (width 0) (type default))
  )
  (bus (pts (xy 140.335 149.86) (xy 140.335 154.94))
    (stroke (width 0) (type default))
  )

  (wire (pts (xy 135.89 107.95) (xy 152.4 107.95))
    (stroke (width 0) (type default))
  )
  (wire (pts (xy 237.49 158.115) (xy 237.49 168.275))
    (stroke (width 0) (type default))
  )
  (wire (pts (xy 170.18 107.95) (xy 179.07 107.95))
    (stroke (width 0) (type default))
  )
  (wire (pts (xy 197.485 170.18) (xy 196.215 170.18))
    (stroke (width 0) (type default))
  )
  (wire (pts (xy 234.315 106.045) (xy 249.555 106.045))
    (stroke (width 0) (type default))
  )
  (wire (pts (xy 170.18 115.57) (xy 172.085 115.57))
    (stroke (width 0) (type default))
  )
  (bus (pts (xy 140.335 160.02) (xy 140.335 162.56))
    (stroke (width 0) (type default))
  )

  (wire (pts (xy 234.315 95.25) (xy 234.315 97.155))
    (stroke (width 0) (type default))
  )
  (wire (pts (xy 226.06 95.25) (xy 226.06 93.345))
    (stroke (width 0) (type default))
  )
  (wire (pts (xy 179.07 189.23) (xy 179.07 191.135))
    (stroke (width 0) (type default))
  )
  (wire (pts (xy 215.265 173.99) (xy 217.805 173.99))
    (stroke (width 0) (type default))
  )
  (bus (pts (xy 140.335 147.32) (xy 140.335 149.86))
    (stroke (width 0) (type default))
  )

  (wire (pts (xy 234.315 95.25) (xy 241.935 95.25))
    (stroke (width 0) (type default))
  )
  (wire (pts (xy 217.805 180.975) (xy 217.805 182.88))
    (stroke (width 0) (type default))
  )
  (wire (pts (xy 177.165 152.4) (xy 168.275 152.4))
    (stroke (width 0) (type default))
  )
  (wire (pts (xy 226.695 182.88) (xy 226.695 165.735))
    (stroke (width 0) (type default))
  )
  (wire (pts (xy 217.17 110.49) (xy 218.44 110.49))
    (stroke (width 0) (type default))
  )
  (wire (pts (xy 197.485 171.45) (xy 197.485 170.18))
    (stroke (width 0) (type default))
  )
  (wire (pts (xy 196.215 152.4) (xy 205.105 152.4))
    (stroke (width 0) (type default))
  )
  (wire (pts (xy 234.315 102.235) (xy 234.315 106.045))
    (stroke (width 0) (type default))
  )
  (wire (pts (xy 226.06 85.725) (xy 220.98 85.725))
    (stroke (width 0) (type default))
  )
  (wire (pts (xy 142.875 165.1) (xy 160.655 165.1))
    (stroke (width 0) (type default))
  )
  (wire (pts (xy 267.97 107.95) (xy 267.97 106.045))
    (stroke (width 0) (type default))
  )
  (wire (pts (xy 239.395 158.115) (xy 237.49 158.115))
    (stroke (width 0) (type default))
  )
  (wire (pts (xy 198.12 189.23) (xy 198.12 191.135))
    (stroke (width 0) (type default))
  )
  (wire (pts (xy 168.91 81.28) (xy 174.625 81.28))
    (stroke (width 0) (type default))
  )
  (wire (pts (xy 260.985 165.735) (xy 263.525 165.735))
    (stroke (width 0) (type default))
  )
  (wire (pts (xy 237.49 168.275) (xy 237.49 170.815))
    (stroke (width 0) (type default))
  )
  (wire (pts (xy 249.555 106.045) (xy 256.54 106.045))
    (stroke (width 0) (type default))
  )
  (wire (pts (xy 217.805 182.88) (xy 226.695 182.88))
    (stroke (width 0) (type default))
  )
  (wire (pts (xy 184.785 101.6) (xy 184.785 103.505))
    (stroke (width 0) (type default))
  )
  (wire (pts (xy 226.06 95.25) (xy 226.06 97.155))
    (stroke (width 0) (type default))
  )
  (wire (pts (xy 226.06 102.235) (xy 226.06 102.87))
    (stroke (width 0) (type default))
  )
  (wire (pts (xy 170.815 165.1) (xy 177.165 165.1))
    (stroke (width 0) (type default))
  )
  (wire (pts (xy 170.815 160.02) (xy 177.165 160.02))
    (stroke (width 0) (type default))
  )
  (wire (pts (xy 263.525 165.735) (xy 263.525 170.815))
    (stroke (width 0) (type default))
  )
  (wire (pts (xy 142.875 162.56) (xy 160.655 162.56))
    (stroke (width 0) (type default))
  )
  (wire (pts (xy 137.16 110.49) (xy 152.4 110.49))
    (stroke (width 0) (type default))
  )
  (wire (pts (xy 226.695 155.575) (xy 239.395 155.575))
    (stroke (width 0) (type default))
  )
  (wire (pts (xy 239.395 168.275) (xy 237.49 168.275))
    (stroke (width 0) (type default))
  )
  (wire (pts (xy 239.395 153.035) (xy 226.695 153.035))
    (stroke (width 0) (type default))
  )
  (bus (pts (xy 140.335 162.56) (xy 140.335 180.34))
    (stroke (width 0) (type default))
  )

  (wire (pts (xy 196.215 144.78) (xy 205.105 144.78))
    (stroke (width 0) (type default))
  )
  (wire (pts (xy 234.315 85.725) (xy 249.555 85.725))
    (stroke (width 0) (type default))
  )
  (wire (pts (xy 234.315 88.265) (xy 234.315 85.725))
    (stroke (width 0) (type default))
  )
  (wire (pts (xy 226.695 160.655) (xy 239.395 160.655))
    (stroke (width 0) (type default))
  )
  (wire (pts (xy 170.815 157.48) (xy 177.165 157.48))
    (stroke (width 0) (type default))
  )
  (wire (pts (xy 256.54 106.045) (xy 256.54 107.95))
    (stroke (width 0) (type default))
  )
  (wire (pts (xy 226.695 147.955) (xy 239.395 147.955))
    (stroke (width 0) (type default))
  )
  (wire (pts (xy 226.695 165.735) (xy 239.395 165.735))
    (stroke (width 0) (type default))
  )
  (wire (pts (xy 142.875 152.4) (xy 163.195 152.4))
    (stroke (width 0) (type default))
  )
  (wire (pts (xy 137.16 81.28) (xy 139.7 81.28))
    (stroke (width 0) (type default))
  )
  (wire (pts (xy 152.4 113.03) (xy 148.59 113.03))
    (stroke (width 0) (type default))
  )
  (wire (pts (xy 226.695 150.495) (xy 239.395 150.495))
    (stroke (width 0) (type default))
  )
  (wire (pts (xy 142.875 149.86) (xy 163.195 149.86))
    (stroke (width 0) (type default))
  )

  (text "SD 3.0" (at 180.975 72.39 0)
    (effects (font (size 2.54 2.54) (thickness 0.508) bold) (justify left bottom))
  )
  (text "Power multiplexer (low voltage signaling for SD 3.0 enabled by MIO39)"
    (at 123.825 130.175 0)
    (effects (font (size 1.27 1.27)) (justify left bottom))
  )
  (text "VCCB:\n- 1V8 for SEL= H\n- 3V3 for SEL= L" (at 123.825 136.525 0)
    (effects (font (size 1.27 1.27)) (justify left bottom))
  )

  (label "MIO47" (at 142.875 160.02 0) (fields_autoplaced)
    (effects (font (size 1.27 1.27)) (justify left bottom))
  )
  (label "MIO49" (at 142.875 165.1 0) (fields_autoplaced)
    (effects (font (size 1.27 1.27)) (justify left bottom))
  )
  (label "SD_VDD" (at 276.86 106.045 180) (fields_autoplaced)
    (effects (font (size 1.27 1.27)) (justify right bottom))
  )
  (label "VCCB" (at 179.07 107.95 180) (fields_autoplaced)
    (effects (font (size 1.27 1.27)) (justify right bottom))
  )
  (label "MIO46" (at 142.875 157.48 0) (fields_autoplaced)
    (effects (font (size 1.27 1.27)) (justify left bottom))
  )
  (label "VCCB" (at 168.91 81.28 0) (fields_autoplaced)
    (effects (font (size 1.27 1.27)) (justify left bottom))
  )
  (label "SD_CMD" (at 205.105 149.86 180) (fields_autoplaced)
    (effects (font (size 1.27 1.27)) (justify right bottom))
  )
  (label "MIO51" (at 142.875 152.4 0) (fields_autoplaced)
    (effects (font (size 1.27 1.27)) (justify left bottom))
  )
  (label "SD_DAT3" (at 226.695 147.955 0) (fields_autoplaced)
    (effects (font (size 1.27 1.27)) (justify left bottom))
  )
  (label "SD_DAT1" (at 205.105 160.02 180) (fields_autoplaced)
    (effects (font (size 1.27 1.27)) (justify right bottom))
  )
  (label "SD_DAT1" (at 226.695 163.195 0) (fields_autoplaced)
    (effects (font (size 1.27 1.27)) (justify left bottom))
  )
  (label "VCCB" (at 192.405 189.23 0) (fields_autoplaced)
    (effects (font (size 1.27 1.27)) (justify left bottom))
  )
  (label "SD_DAT2" (at 226.695 145.415 0) (fields_autoplaced)
    (effects (font (size 1.27 1.27)) (justify left bottom))
  )
  (label "MIO48" (at 142.875 162.56 0) (fields_autoplaced)
    (effects (font (size 1.27 1.27)) (justify left bottom))
  )
  (label "MIO50" (at 142.875 149.86 0) (fields_autoplaced)
    (effects (font (size 1.27 1.27)) (justify left bottom))
  )
  (label "SD_CLK" (at 226.695 155.575 0) (fields_autoplaced)
    (effects (font (size 1.27 1.27)) (justify left bottom))
  )
  (label "SD_CMD" (at 226.695 150.495 0) (fields_autoplaced)
    (effects (font (size 1.27 1.27)) (justify left bottom))
  )
  (label "SD_DAT0" (at 226.695 160.655 0) (fields_autoplaced)
    (effects (font (size 1.27 1.27)) (justify left bottom))
  )
  (label "SD_CLK" (at 205.105 152.4 180) (fields_autoplaced)
    (effects (font (size 1.27 1.27)) (justify right bottom))
  )
  (label "SD_DAT0" (at 205.105 157.48 180) (fields_autoplaced)
    (effects (font (size 1.27 1.27)) (justify right bottom))
  )
  (label "SD_DAT3" (at 205.105 165.1 180) (fields_autoplaced)
    (effects (font (size 1.27 1.27)) (justify right bottom))
  )
  (label "SD_VDD" (at 226.695 153.035 0) (fields_autoplaced)
    (effects (font (size 1.27 1.27)) (justify left bottom))
  )
  (label "MIO45" (at 142.875 182.88 0) (fields_autoplaced)
    (effects (font (size 1.27 1.27)) (justify left bottom))
  )
  (label "SD_DAT2" (at 205.105 162.56 180) (fields_autoplaced)
    (effects (font (size 1.27 1.27)) (justify right bottom))
  )
  (label "VCCB" (at 205.105 144.78 180) (fields_autoplaced)
    (effects (font (size 1.27 1.27)) (justify right bottom))
  )

  (global_label "PS_1V8" (shape input) (at 155.575 81.28 180) (fields_autoplaced)
    (effects (font (size 1.27 1.27)) (justify right))
    (property "Intersheetrefs" "${INTERSHEET_REFS}" (at 93.345 167.64 0)
      (effects (font (size 1.27 1.27)) hide)
    )
  )
  (global_label "PS_1V8" (shape input) (at 176.53 189.23 180) (fields_autoplaced)
    (effects (font (size 1.27 1.27)) (justify right))
    (property "Intersheetrefs" "${INTERSHEET_REFS}" (at 12.7 275.59 0)
      (effects (font (size 1.27 1.27)) hide)
    )
  )
  (global_label "PS_1V8" (shape input) (at 182.88 101.6 180) (fields_autoplaced)
    (effects (font (size 1.27 1.27)) (justify right))
    (property "Intersheetrefs" "${INTERSHEET_REFS}" (at 101.6 17.78 0)
      (effects (font (size 1.27 1.27)) hide)
    )
  )
  (global_label "PS_3V3" (shape input) (at 137.16 81.28 180) (fields_autoplaced)
    (effects (font (size 1.27 1.27)) (justify right))
    (property "Intersheetrefs" "${INTERSHEET_REFS}" (at 74.93 154.94 0)
      (effects (font (size 1.27 1.27)) hide)
    )
  )
  (global_label "PS_1V8" (shape input) (at 173.355 144.78 180) (fields_autoplaced)
    (effects (font (size 1.27 1.27)) (justify right))
    (property "Intersheetrefs" "${INTERSHEET_REFS}" (at 83.185 30.48 0)
      (effects (font (size 1.27 1.27)) hide)
    )
  )
  (global_label "PS_1V8" (shape input) (at 215.265 173.99 180) (fields_autoplaced)
    (effects (font (size 1.27 1.27)) (justify right))
    (property "Intersheetrefs" "${INTERSHEET_REFS}" (at 8.255 31.75 0)
      (effects (font (size 1.27 1.27)) hide)
    )
  )
  (global_label "PS_3V3" (shape input) (at 220.98 85.725 180) (fields_autoplaced)
    (effects (font (size 1.27 1.27)) (justify right))
    (property "Intersheetrefs" "${INTERSHEET_REFS}" (at 165.1 302.895 0)
      (effects (font (size 1.27 1.27)) hide)
    )
  )
  (global_label "PS_3V3" (shape input) (at 135.89 110.49 180) (fields_autoplaced)
    (effects (font (size 1.27 1.27)) (justify right))
    (property "Intersheetrefs" "${INTERSHEET_REFS}" (at 54.61 24.13 0)
      (effects (font (size 1.27 1.27)) hide)
    )
  )
  (global_label "PS_1V8" (shape input) (at 135.89 107.95 180) (fields_autoplaced)
    (effects (font (size 1.27 1.27)) (justify right))
    (property "Intersheetrefs" "${INTERSHEET_REFS}" (at 54.61 24.13 0)
      (effects (font (size 1.27 1.27)) hide)
    )
  )

  (hierarchical_label "MIO39" (shape input) (at 148.59 113.03 180) (fields_autoplaced)
    (effects (font (size 1.27 1.27)) (justify right))
  )
  (hierarchical_label "~{SD_CARD_RESET}" (shape input) (at 217.17 110.49 180) (fields_autoplaced)
    (effects (font (size 1.27 1.27)) (justify right))
  )
  (hierarchical_label "MIO[45..51]" (shape input) (at 133.985 143.51 180) (fields_autoplaced)
    (effects (font (size 1.27 1.27)) (justify right))
  )

  (symbol (lib_id "kria-k26-devboard:NVT4858_XQFN") (at 177.165 144.78 0) (unit 1)
    (in_bom yes) (on_board yes) (dnp no)
    (property "Reference" "U5" (at 186.69 137.16 0)
      (effects (font (size 1.524 1.524)))
    )
    (property "Value" "NVT4858_XQFN" (at 186.69 139.7 0)
      (effects (font (size 1.27 1.27) (thickness 0.15)) hide)
    )
    (property "Footprint" "kria-k26-devboard-footprints:SOT1161-2" (at 230.505 152.4 0)
      (effects (font (size 1.27 1.27) (thickness 0.15)) (justify left bottom) hide)
    )
    (property "Datasheet" "https://www.nxp.com/docs/en/data-sheet/NVT4858DS.pdf" (at 230.505 154.94 0)
      (effects (font (size 1.27 1.27) (thickness 0.15)) (justify left bottom) hide)
    )
    (property "Manufacturer" "NXP" (at 230.505 157.48 0)
      (effects (font (size 1.27 1.27) (thickness 0.15)) (justify left bottom) hide)
    )
    (property "MPN" "NVT4858HKZ" (at 186.69 139.7 0)
      (effects (font (size 1.27 1.27)))
    )
    (property "Author" "Antmicro" (at 230.505 162.56 0)
      (effects (font (size 1.27 1.27) (thickness 0.15)) (justify left bottom) hide)
    )
    (property "License" "Apache-2.0" (at 230.505 165.1 0)
      (effects (font (size 1.27 1.27) (thickness 0.15)) (justify left bottom) hide)
    )
    (pin "1")
    (pin "10")
    (pin "11")
    (pin "12")
    (pin "13")
    (pin "14")
    (pin "15")
    (pin "16")
    (pin "2")
    (pin "3")
    (pin "4")
    (pin "5")
    (pin "6")
    (pin "7")
    (pin "8")
    (pin "9")
    (instances
      (project "kria-k26-devboard"
        (path ""
          (reference "U5") (unit 1)
        )
      )
    )
  )

  (symbol (lib_id "kria-k26-devboard:MicroSD_1140084168") (at 239.395 145.415 0) (unit 1)
    (in_bom yes) (on_board yes) (dnp no) (fields_autoplaced)
    (property "Reference" "J2" (at 252.73 137.16 0)
      (effects (font (size 1.27 1.27)))
    )
    (property "Value" "MicroSD_1140084168" (at 252.73 140.335 0)
      (effects (font (size 1.27 1.27) (thickness 0.15)) hide)
    )
    (property "Footprint" "kria-k26-devboard-footprints:MicroSD_Amphenol_1140084168" (at 277.495 154.305 0)
      (effects (font (size 1.27 1.27) (thickness 0.15)) (justify left bottom) hide)
    )
    (property "Datasheet" "https://cdn.amphenol-cs.com/media/wysiwyg/files/documentation/datasheet/inputoutput/io_micro_sdcard.pdf" (at 277.495 156.845 0)
      (effects (font (size 1.27 1.27) (thickness 0.15)) (justify left bottom) hide)
    )
    (property "MPN" "1140084168" (at 252.73 139.7 0)
      (effects (font (size 1.27 1.27) (thickness 0.15)))
    )
    (property "Manufacturer" "Amphenol" (at 277.495 161.925 0)
      (effects (font (size 1.27 1.27) (thickness 0.15)) (justify left bottom) hide)
    )
    (property "Author" "Antmicro" (at 277.495 164.465 0)
      (effects (font (size 1.27 1.27) (thickness 0.15)) (justify left bottom) hide)
    )
    (property "License" "Apache-2.0" (at 277.495 167.005 0)
      (effects (font (size 1.27 1.27) (thickness 0.15)) (justify left bottom) hide)
    )
    (pin "1")
    (pin "10")
    (pin "2")
    (pin "3")
    (pin "4")
    (pin "5")
    (pin "6")
    (pin "7")
    (pin "8")
    (pin "9")
    (pin "SH")
    (instances
      (project "kria-k26-devboard"
        (path ""
          (reference "J2") (unit 1)
        )
      )
    )
  )

  (symbol (lib_id "kria-k26-devboard:TPS2116DRLR") (at 152.4 107.95 0) (unit 1)
    (in_bom yes) (on_board yes) (dnp no)
    (property "Reference" "U6" (at 161.29 100.33 0)
      (effects (font (size 1.524 1.524)))
    )
    (property "Value" "TPS2116DRLR" (at 161.29 102.87 0)
      (effects (font (size 1.27 1.27) (thickness 0.15)))
    )
    (property "Footprint" "kria-k26-devboard-footprints:SOT-583" (at 186.69 113.03 0)
      (effects (font (size 1.27 1.27) (thickness 0.15)) (justify left bottom) hide)
    )
    (property "Datasheet" "https://www.ti.com/lit/ds/symlink/tps2116.pdf?ts=1647438832100&ref_url=https%253A%252F%252Fwww.ti.com%252Fproduct%252FTPS2116" (at 186.69 115.57 0)
      (effects (font (size 1.27 1.27) (thickness 0.15)) (justify left bottom) hide)
    )
    (property "Manufacturer" "Texas Instruments" (at 186.69 118.11 0)
      (effects (font (size 1.27 1.27) (thickness 0.15)) (justify left bottom) hide)
    )
    (property "MPN" "TPS2116DRLR" (at 186.69 120.65 0)
      (effects (font (size 1.27 1.27) (thickness 0.15)) (justify left bottom) hide)
    )
    (property "Author" "Antmicro" (at 186.69 123.19 0)
      (effects (font (size 1.27 1.27) (thickness 0.15)) (justify left bottom) hide)
    )
    (property "License" "Apache-2.0" (at 186.69 125.73 0)
      (effects (font (size 1.27 1.27) (thickness 0.15)) (justify left bottom) hide)
    )
    (pin "1")
    (pin "2")
    (pin "3")
    (pin "4")
    (pin "5")
    (pin "6")
    (pin "7")
    (pin "8")
    (instances
      (project "kria-k26-devboard"
        (path ""
          (reference "U6") (unit 1)
        )
      )
    )
  )

  (symbol (lib_id "kria-k26-devboard:GND") (at 172.085 116.84 0) (unit 1)
    (in_bom yes) (on_board yes) (dnp no) (fields_autoplaced)
    (property "Reference" "#PWR027" (at 172.085 123.19 0)
      (effects (font (size 1.27 1.27)) hide)
    )
    (property "Value" "GND" (at 172.085 121.92 0)
      (effects (font (size 1.27 1.27)))
    )
    (property "Footprint" "" (at 180.975 124.46 0)
      (effects (font (size 1.27 1.27) (thickness 0.15)) (justify left bottom) hide)
    )
    (property "Datasheet" "" (at 180.975 129.54 0)
      (effects (font (size 1.27 1.27) (thickness 0.15)) (justify left bottom) hide)
    )
    (property "Author" "Antmicro" (at 180.975 124.46 0)
      (effects (font (size 1.27 1.27) (thickness 0.15)) (justify left bottom) hide)
    )
    (property "License" "Apache-2.0" (at 180.975 127 0)
      (effects (font (size 1.27 1.27) (thickness 0.15)) (justify left bottom) hide)
    )
    (pin "1")
    (instances
      (project "kria-k26-devboard"
        (path ""
          (reference "#PWR027") (unit 1)
        )
      )
    )
  )

  (symbol (lib_id "kria-k26-devboard:R_33R_0402") (at 163.195 152.4 0) (unit 1)
    (in_bom yes) (on_board yes) (dnp no)
    (property "Reference" "R14" (at 161.29 151.13 0)
      (effects (font (size 1.524 1.524)))
    )
    (property "Value" "R_33R_0402" (at 183.515 165.1 0)
      (effects (font (size 1.27 1.27) (thickness 0.15)) (justify left bottom) hide)
    )
    (property "Footprint" "kria-k26-devboard-footprints:R_0402_1005Metric" (at 183.515 167.64 0)
      (effects (font (size 1.27 1.27) (thickness 0.15)) (justify left bottom) hide)
    )
    (property "Datasheet" "https://www.bourns.com/docs/product-datasheets/cr.pdf" (at 183.515 170.18 0)
      (effects (font (size 1.27 1.27) (thickness 0.15)) (justify left bottom) hide)
    )
    (property "Manufacturer" "Bourns" (at 183.515 175.26 0)
      (effects (font (size 1.27 1.27) (thickness 0.15)) (justify left bottom) hide)
    )
    (property "MPN" "CR0402-FX-33R0GLF" (at 183.515 172.72 0)
      (effects (font (size 1.27 1.27) (thickness 0.15)) (justify left bottom) hide)
    )
    (property "Val" "33R" (at 170.18 151.13 0)
      (effects (font (size 1.27 1.27) (thickness 0.15)))
    )
    (property "License" "Apache-2.0" (at 183.515 177.8 0)
      (effects (font (size 1.27 1.27) (thickness 0.15)) (justify left bottom) hide)
    )
    (property "Author" "Antmicro" (at 183.515 180.34 0)
      (effects (font (size 1.27 1.27) (thickness 0.15)) (justify left bottom) hide)
    )
    (property "Tolerance" "1%" (at 183.515 162.56 0)
      (effects (font (size 1.27 1.27)) (justify left bottom) hide)
    )
    (pin "1")
    (pin "2")
    (instances
      (project "kria-k26-devboard"
        (path ""
          (reference "R14") (unit 1)
        )
      )
    )
  )

  (symbol (lib_id "kria-k26-devboard:R_33R_0402") (at 163.195 149.86 0) (unit 1)
    (in_bom yes) (on_board yes) (dnp no)
    (property "Reference" "R13" (at 161.29 148.59 0)
      (effects (font (size 1.524 1.524)))
    )
    (property "Value" "R_33R_0402" (at 183.515 162.56 0)
      (effects (font (size 1.27 1.27) (thickness 0.15)) (justify left bottom) hide)
    )
    (property "Footprint" "kria-k26-devboard-footprints:R_0402_1005Metric" (at 183.515 165.1 0)
      (effects (font (size 1.27 1.27) (thickness 0.15)) (justify left bottom) hide)
    )
    (property "Datasheet" "https://www.bourns.com/docs/product-datasheets/cr.pdf" (at 183.515 167.64 0)
      (effects (font (size 1.27 1.27) (thickness 0.15)) (justify left bottom) hide)
    )
    (property "Manufacturer" "Bourns" (at 183.515 172.72 0)
      (effects (font (size 1.27 1.27) (thickness 0.15)) (justify left bottom) hide)
    )
    (property "MPN" "CR0402-FX-33R0GLF" (at 183.515 170.18 0)
      (effects (font (size 1.27 1.27) (thickness 0.15)) (justify left bottom) hide)
    )
    (property "Val" "33R" (at 170.18 148.59 0)
      (effects (font (size 1.27 1.27) (thickness 0.15)))
    )
    (property "License" "Apache-2.0" (at 183.515 175.26 0)
      (effects (font (size 1.27 1.27) (thickness 0.15)) (justify left bottom) hide)
    )
    (property "Author" "Antmicro" (at 183.515 177.8 0)
      (effects (font (size 1.27 1.27) (thickness 0.15)) (justify left bottom) hide)
    )
    (property "Tolerance" "1%" (at 183.515 160.02 0)
      (effects (font (size 1.27 1.27)) (justify left bottom) hide)
    )
    (pin "1")
    (pin "2")
    (instances
      (project "kria-k26-devboard"
        (path ""
          (reference "R13") (unit 1)
        )
      )
    )
  )

  (symbol (lib_id "kria-k26-devboard:GND") (at 197.485 171.45 0) (unit 1)
    (in_bom yes) (on_board yes) (dnp no) (fields_autoplaced)
    (property "Reference" "#PWR028" (at 197.485 177.8 0)
      (effects (font (size 1.27 1.27)) hide)
    )
    (property "Value" "GND" (at 197.485 176.53 0)
      (effects (font (size 1.27 1.27)))
    )
    (property "Footprint" "" (at 206.375 179.07 0)
      (effects (font (size 1.27 1.27) (thickness 0.15)) (justify left bottom) hide)
    )
    (property "Datasheet" "" (at 206.375 184.15 0)
      (effects (font (size 1.27 1.27) (thickness 0.15)) (justify left bottom) hide)
    )
    (property "Author" "Antmicro" (at 206.375 179.07 0)
      (effects (font (size 1.27 1.27) (thickness 0.15)) (justify left bottom) hide)
    )
    (property "License" "Apache-2.0" (at 206.375 181.61 0)
      (effects (font (size 1.27 1.27) (thickness 0.15)) (justify left bottom) hide)
    )
    (pin "1")
    (instances
      (project "kria-k26-devboard"
        (path ""
          (reference "#PWR028") (unit 1)
        )
      )
    )
  )

  (symbol (lib_id "kria-k26-devboard:C_100n_0402") (at 139.7 83.185 270) (unit 1)
    (in_bom yes) (on_board yes) (dnp no) (fields_autoplaced)
    (property "Reference" "C12" (at 142.24 84.4613 90)
      (effects (font (size 1.524 1.524)) (justify left))
    )
    (property "Value" "C_100n_0402" (at 129.54 103.505 0)
      (effects (font (size 1.27 1.27) (thickness 0.15)) (justify left bottom) hide)
    )
    (property "Footprint" "kria-k26-devboard-footprints:C_0402_1005Metric" (at 127 103.505 0)
      (effects (font (size 1.27 1.27) (thickness 0.15)) (justify left bottom) hide)
    )
    (property "Datasheet" "https://search.murata.co.jp/Ceramy/image/img/A01X/G101/ENG/GRM155R61H104KE14-01.pdf" (at 124.46 103.505 0)
      (effects (font (size 1.27 1.27) (thickness 0.15)) (justify left bottom) hide)
    )
    (property "Manufacturer" "Murata" (at 119.38 103.505 0)
      (effects (font (size 1.27 1.27) (thickness 0.15)) (justify left bottom) hide)
    )
    (property "MPN" "GRM155R61H104KE14D" (at 121.92 103.505 0)
      (effects (font (size 1.27 1.27) (thickness 0.15)) (justify left bottom) hide)
    )
    (property "Val" "100n" (at 142.24 87.6362 90)
      (effects (font (size 1.27 1.27) (thickness 0.15)) (justify left))
    )
    (property "License" "Apache-2.0" (at 116.84 103.505 0)
      (effects (font (size 1.27 1.27) (thickness 0.15)) (justify left bottom) hide)
    )
    (property "Author" "Antmicro" (at 114.3 103.505 0)
      (effects (font (size 1.27 1.27) (thickness 0.15)) (justify left bottom) hide)
    )
    (property "Voltage" "50V" (at 111.76 103.505 0)
      (effects (font (size 1.27 1.27)) (justify left bottom) hide)
    )
    (property "Dielectric" "X5R" (at 109.22 103.505 0)
      (effects (font (size 1.27 1.27)) (justify left bottom) hide)
    )
    (pin "1")
    (pin "2")
    (instances
      (project "kria-k26-devboard"
        (path ""
          (reference "C12") (unit 1)
        )
      )
    )
  )

  (symbol (lib_id "kria-k26-devboard:C_100n_0402") (at 158.115 83.185 270) (unit 1)
    (in_bom yes) (on_board yes) (dnp no) (fields_autoplaced)
    (property "Reference" "C13" (at 160.655 84.4613 90)
      (effects (font (size 1.524 1.524)) (justify left))
    )
    (property "Value" "C_100n_0402" (at 147.955 103.505 0)
      (effects (font (size 1.27 1.27) (thickness 0.15)) (justify left bottom) hide)
    )
    (property "Footprint" "kria-k26-devboard-footprints:C_0402_1005Metric" (at 145.415 103.505 0)
      (effects (font (size 1.27 1.27) (thickness 0.15)) (justify left bottom) hide)
    )
    (property "Datasheet" "https://search.murata.co.jp/Ceramy/image/img/A01X/G101/ENG/GRM155R61H104KE14-01.pdf" (at 142.875 103.505 0)
      (effects (font (size 1.27 1.27) (thickness 0.15)) (justify left bottom) hide)
    )
    (property "Manufacturer" "Murata" (at 137.795 103.505 0)
      (effects (font (size 1.27 1.27) (thickness 0.15)) (justify left bottom) hide)
    )
    (property "MPN" "GRM155R61H104KE14D" (at 140.335 103.505 0)
      (effects (font (size 1.27 1.27) (thickness 0.15)) (justify left bottom) hide)
    )
    (property "Val" "100n" (at 160.655 87.6362 90)
      (effects (font (size 1.27 1.27) (thickness 0.15)) (justify left))
    )
    (property "License" "Apache-2.0" (at 135.255 103.505 0)
      (effects (font (size 1.27 1.27) (thickness 0.15)) (justify left bottom) hide)
    )
    (property "Author" "Antmicro" (at 132.715 103.505 0)
      (effects (font (size 1.27 1.27) (thickness 0.15)) (justify left bottom) hide)
    )
    (property "Voltage" "50V" (at 130.175 103.505 0)
      (effects (font (size 1.27 1.27)) (justify left bottom) hide)
    )
    (property "Dielectric" "X5R" (at 127.635 103.505 0)
      (effects (font (size 1.27 1.27)) (justify left bottom) hide)
    )
    (pin "1")
    (pin "2")
    (instances
      (project "kria-k26-devboard"
        (path ""
          (reference "C13") (unit 1)
        )
      )
    )
  )

  (symbol (lib_id "kria-k26-devboard:C_100n_0402") (at 174.625 83.185 270) (unit 1)
    (in_bom yes) (on_board yes) (dnp no) (fields_autoplaced)
    (property "Reference" "C15" (at 177.8 84.4613 90)
      (effects (font (size 1.524 1.524)) (justify left))
    )
    (property "Value" "C_100n_0402" (at 164.465 103.505 0)
      (effects (font (size 1.27 1.27) (thickness 0.15)) (justify left bottom) hide)
    )
    (property "Footprint" "kria-k26-devboard-footprints:C_0402_1005Metric" (at 161.925 103.505 0)
      (effects (font (size 1.27 1.27) (thickness 0.15)) (justify left bottom) hide)
    )
    (property "Datasheet" "https://search.murata.co.jp/Ceramy/image/img/A01X/G101/ENG/GRM155R61H104KE14-01.pdf" (at 159.385 103.505 0)
      (effects (font (size 1.27 1.27) (thickness 0.15)) (justify left bottom) hide)
    )
    (property "Manufacturer" "Murata" (at 154.305 103.505 0)
      (effects (font (size 1.27 1.27) (thickness 0.15)) (justify left bottom) hide)
    )
    (property "MPN" "GRM155R61H104KE14D" (at 156.845 103.505 0)
      (effects (font (size 1.27 1.27) (thickness 0.15)) (justify left bottom) hide)
    )
    (property "Val" "100n" (at 177.8 87.6362 90)
      (effects (font (size 1.27 1.27) (thickness 0.15)) (justify left))
    )
    (property "License" "Apache-2.0" (at 151.765 103.505 0)
      (effects (font (size 1.27 1.27) (thickness 0.15)) (justify left bottom) hide)
    )
    (property "Author" "Antmicro" (at 149.225 103.505 0)
      (effects (font (size 1.27 1.27) (thickness 0.15)) (justify left bottom) hide)
    )
    (property "Voltage" "50V" (at 146.685 103.505 0)
      (effects (font (size 1.27 1.27)) (justify left bottom) hide)
    )
    (property "Dielectric" "X5R" (at 144.145 103.505 0)
      (effects (font (size 1.27 1.27)) (justify left bottom) hide)
    )
    (pin "1")
    (pin "2")
    (instances
      (project "kria-k26-devboard"
        (path ""
          (reference "C15") (unit 1)
        )
      )
    )
  )

  (symbol (lib_id "kria-k26-devboard:GND") (at 139.7 88.265 0) (unit 1)
    (in_bom yes) (on_board yes) (dnp no) (fields_autoplaced)
    (property "Reference" "#PWR024" (at 139.7 94.615 0)
      (effects (font (size 1.27 1.27)) hide)
    )
    (property "Value" "GND" (at 139.7 93.345 0)
      (effects (font (size 1.27 1.27)))
    )
    (property "Footprint" "" (at 148.59 95.885 0)
      (effects (font (size 1.27 1.27) (thickness 0.15)) (justify left bottom) hide)
    )
    (property "Datasheet" "" (at 148.59 100.965 0)
      (effects (font (size 1.27 1.27) (thickness 0.15)) (justify left bottom) hide)
    )
    (property "Author" "Antmicro" (at 148.59 95.885 0)
      (effects (font (size 1.27 1.27) (thickness 0.15)) (justify left bottom) hide)
    )
    (property "License" "Apache-2.0" (at 148.59 98.425 0)
      (effects (font (size 1.27 1.27) (thickness 0.15)) (justify left bottom) hide)
    )
    (pin "1")
    (instances
      (project "kria-k26-devboard"
        (path ""
          (reference "#PWR024") (unit 1)
        )
      )
    )
  )

  (symbol (lib_id "kria-k26-devboard:GND") (at 158.115 88.265 0) (unit 1)
    (in_bom yes) (on_board yes) (dnp no) (fields_autoplaced)
    (property "Reference" "#PWR025" (at 158.115 94.615 0)
      (effects (font (size 1.27 1.27)) hide)
    )
    (property "Value" "GND" (at 158.115 93.345 0)
      (effects (font (size 1.27 1.27)))
    )
    (property "Footprint" "" (at 167.005 95.885 0)
      (effects (font (size 1.27 1.27) (thickness 0.15)) (justify left bottom) hide)
    )
    (property "Datasheet" "" (at 167.005 100.965 0)
      (effects (font (size 1.27 1.27) (thickness 0.15)) (justify left bottom) hide)
    )
    (property "Author" "Antmicro" (at 167.005 95.885 0)
      (effects (font (size 1.27 1.27) (thickness 0.15)) (justify left bottom) hide)
    )
    (property "License" "Apache-2.0" (at 167.005 98.425 0)
      (effects (font (size 1.27 1.27) (thickness 0.15)) (justify left bottom) hide)
    )
    (pin "1")
    (instances
      (project "kria-k26-devboard"
        (path ""
          (reference "#PWR025") (unit 1)
        )
      )
    )
  )

  (symbol (lib_id "kria-k26-devboard:C_100n_0402") (at 256.54 107.95 270) (unit 1)
    (in_bom yes) (on_board yes) (dnp no) (fields_autoplaced)
    (property "Reference" "C19" (at 259.08 109.2263 90)
      (effects (font (size 1.524 1.524)) (justify left))
    )
    (property "Value" "C_100n_0402" (at 246.38 128.27 0)
      (effects (font (size 1.27 1.27) (thickness 0.15)) (justify left bottom) hide)
    )
    (property "Footprint" "kria-k26-devboard-footprints:C_0402_1005Metric" (at 243.84 128.27 0)
      (effects (font (size 1.27 1.27) (thickness 0.15)) (justify left bottom) hide)
    )
    (property "Datasheet" "https://search.murata.co.jp/Ceramy/image/img/A01X/G101/ENG/GRM155R61H104KE14-01.pdf" (at 241.3 128.27 0)
      (effects (font (size 1.27 1.27) (thickness 0.15)) (justify left bottom) hide)
    )
    (property "Manufacturer" "Murata" (at 236.22 128.27 0)
      (effects (font (size 1.27 1.27) (thickness 0.15)) (justify left bottom) hide)
    )
    (property "MPN" "GRM155R61H104KE14D" (at 238.76 128.27 0)
      (effects (font (size 1.27 1.27) (thickness 0.15)) (justify left bottom) hide)
    )
    (property "Val" "100n" (at 259.08 112.4012 90)
      (effects (font (size 1.27 1.27) (thickness 0.15)) (justify left))
    )
    (property "License" "Apache-2.0" (at 233.68 128.27 0)
      (effects (font (size 1.27 1.27) (thickness 0.15)) (justify left bottom) hide)
    )
    (property "Author" "Antmicro" (at 231.14 128.27 0)
      (effects (font (size 1.27 1.27) (thickness 0.15)) (justify left bottom) hide)
    )
    (property "Voltage" "50V" (at 228.6 128.27 0)
      (effects (font (size 1.27 1.27)) (justify left bottom) hide)
    )
    (property "Dielectric" "X5R" (at 226.06 128.27 0)
      (effects (font (size 1.27 1.27)) (justify left bottom) hide)
    )
    (pin "1")
    (pin "2")
    (instances
      (project "kria-k26-devboard"
        (path ""
          (reference "C19") (unit 1)
        )
      )
    )
  )

  (symbol (lib_id "kria-k26-devboard:GND") (at 256.54 113.03 0) (unit 1)
    (in_bom yes) (on_board yes) (dnp no) (fields_autoplaced)
    (property "Reference" "#PWR032" (at 256.54 119.38 0)
      (effects (font (size 1.27 1.27)) hide)
    )
    (property "Value" "GND" (at 256.54 118.11 0)
      (effects (font (size 1.27 1.27)))
    )
    (property "Footprint" "" (at 265.43 120.65 0)
      (effects (font (size 1.27 1.27) (thickness 0.15)) (justify left bottom) hide)
    )
    (property "Datasheet" "" (at 265.43 125.73 0)
      (effects (font (size 1.27 1.27) (thickness 0.15)) (justify left bottom) hide)
    )
    (property "Author" "Antmicro" (at 265.43 120.65 0)
      (effects (font (size 1.27 1.27) (thickness 0.15)) (justify left bottom) hide)
    )
    (property "License" "Apache-2.0" (at 265.43 123.19 0)
      (effects (font (size 1.27 1.27) (thickness 0.15)) (justify left bottom) hide)
    )
    (pin "1")
    (instances
      (project "kria-k26-devboard"
        (path ""
          (reference "#PWR032") (unit 1)
        )
      )
    )
  )

  (symbol (lib_id "kria-k26-devboard:C_10u_0603") (at 267.97 107.95 270) (unit 1)
    (in_bom yes) (on_board yes) (dnp no) (fields_autoplaced)
    (property "Reference" "C20" (at 270.51 109.2263 90)
      (effects (font (size 1.524 1.524)) (justify left))
    )
    (property "Value" "C_10u_0603" (at 257.81 128.27 0)
      (effects (font (size 1.27 1.27) (thickness 0.15)) (justify left bottom) hide)
    )
    (property "Footprint" "kria-k26-devboard-footprints:C_0603_1608Metric" (at 255.27 128.27 0)
      (effects (font (size 1.27 1.27) (thickness 0.15)) (justify left bottom) hide)
    )
    (property "Datasheet" " " (at 252.73 128.27 0)
      (effects (font (size 1.27 1.27) (thickness 0.15)) (justify left bottom) hide)
    )
    (property "Manufacturer" "Murata" (at 247.65 128.27 0)
      (effects (font (size 1.27 1.27) (thickness 0.15)) (justify left bottom) hide)
    )
    (property "MPN" "GRM188R61A106KE69D" (at 250.19 128.27 0)
      (effects (font (size 1.27 1.27) (thickness 0.15)) (justify left bottom) hide)
    )
    (property "Val" "10u" (at 270.51 112.4012 90)
      (effects (font (size 1.27 1.27) (thickness 0.15)) (justify left))
    )
    (property "License" "Apache-2.0" (at 245.11 128.27 0)
      (effects (font (size 1.27 1.27) (thickness 0.15)) (justify left bottom) hide)
    )
    (property "Author" "Antmicro" (at 242.57 128.27 0)
      (effects (font (size 1.27 1.27) (thickness 0.15)) (justify left bottom) hide)
    )
    (property "Voltage" "" (at 240.03 128.27 0)
      (effects (font (size 1.27 1.27)) (justify left bottom) hide)
    )
    (pin "1")
    (pin "2")
    (instances
      (project "kria-k26-devboard"
        (path ""
          (reference "C20") (unit 1)
        )
      )
    )
  )

  (symbol (lib_id "kria-k26-devboard:GND") (at 174.625 88.265 0) (unit 1)
    (in_bom yes) (on_board yes) (dnp no) (fields_autoplaced)
    (property "Reference" "#PWR029" (at 174.625 94.615 0)
      (effects (font (size 1.27 1.27)) hide)
    )
    (property "Value" "GND" (at 174.625 93.345 0)
      (effects (font (size 1.27 1.27)))
    )
    (property "Footprint" "" (at 183.515 95.885 0)
      (effects (font (size 1.27 1.27) (thickness 0.15)) (justify left bottom) hide)
    )
    (property "Datasheet" "" (at 183.515 100.965 0)
      (effects (font (size 1.27 1.27) (thickness 0.15)) (justify left bottom) hide)
    )
    (property "Author" "Antmicro" (at 183.515 95.885 0)
      (effects (font (size 1.27 1.27) (thickness 0.15)) (justify left bottom) hide)
    )
    (property "License" "Apache-2.0" (at 183.515 98.425 0)
      (effects (font (size 1.27 1.27) (thickness 0.15)) (justify left bottom) hide)
    )
    (pin "1")
    (instances
      (project "kria-k26-devboard"
        (path ""
          (reference "#PWR029") (unit 1)
        )
      )
    )
  )

  (symbol (lib_id "kria-k26-devboard:R_10k_0402") (at 217.805 175.895 270) (unit 1)
    (in_bom yes) (on_board yes) (dnp no) (fields_autoplaced)
    (property "Reference" "R18" (at 220.599 177.165 90)
      (effects (font (size 1.524 1.524)) (justify left))
    )
    (property "Value" "R_10k_0402" (at 205.105 196.215 0)
      (effects (font (size 1.27 1.27) (thickness 0.15)) (justify left bottom) hide)
    )
    (property "Footprint" "kria-k26-devboard-footprints:R_0402_1005Metric" (at 202.565 196.215 0)
      (effects (font (size 1.27 1.27) (thickness 0.15)) (justify left bottom) hide)
    )
    (property "Datasheet" "https://www.bourns.com/docs/product-datasheets/cr.pdf" (at 200.025 196.215 0)
      (effects (font (size 1.27 1.27) (thickness 0.15)) (justify left bottom) hide)
    )
    (property "Manufacturer" "Bourns" (at 194.945 196.215 0)
      (effects (font (size 1.27 1.27) (thickness 0.15)) (justify left bottom) hide)
    )
    (property "MPN" "CR0402-FX-1002GLF" (at 197.485 196.215 0)
      (effects (font (size 1.27 1.27) (thickness 0.15)) (justify left bottom) hide)
    )
    (property "Val" "10k" (at 220.599 180.3399 90)
      (effects (font (size 1.27 1.27) (thickness 0.15)) (justify left))
    )
    (property "License" "Apache-2.0" (at 192.405 196.215 0)
      (effects (font (size 1.27 1.27) (thickness 0.15)) (justify left bottom) hide)
    )
    (property "Author" "Antmicro" (at 189.865 196.215 0)
      (effects (font (size 1.27 1.27) (thickness 0.15)) (justify left bottom) hide)
    )
    (property "Tolerance" "1%" (at 207.645 196.215 0)
      (effects (font (size 1.27 1.27)) (justify left bottom) hide)
    )
    (pin "1")
    (pin "2")
    (instances
      (project "kria-k26-devboard"
        (path ""
          (reference "R18") (unit 1)
        )
      )
    )
  )

  (symbol (lib_id "kria-k26-devboard:R_1k_0402") (at 226.06 102.235 90) (unit 1)
    (in_bom yes) (on_board yes) (dnp no) (fields_autoplaced)
    (property "Reference" "R17" (at 223.52 98.425 90)
      (effects (font (size 1.524 1.524)) (justify left))
    )
    (property "Value" "R_1k_0402" (at 238.76 81.915 0)
      (effects (font (size 1.27 1.27) (thickness 0.15)) (justify left bottom) hide)
    )
    (property "Footprint" "kria-k26-devboard-footprints:R_0402_1005Metric" (at 241.3 81.915 0)
      (effects (font (size 1.27 1.27) (thickness 0.15)) (justify left bottom) hide)
    )
    (property "Datasheet" "https://www.bourns.com/docs/product-datasheets/cr.pdf" (at 243.84 81.915 0)
      (effects (font (size 1.27 1.27) (thickness 0.15)) (justify left bottom) hide)
    )
    (property "Manufacturer" "Bourns" (at 248.92 81.915 0)
      (effects (font (size 1.27 1.27) (thickness 0.15)) (justify left bottom) hide)
    )
    (property "MPN" "CR0402-FX-1001GLF" (at 246.38 81.915 0)
      (effects (font (size 1.27 1.27) (thickness 0.15)) (justify left bottom) hide)
    )
    (property "Val" "1k" (at 223.52 101.5999 90)
      (effects (font (size 1.27 1.27) (thickness 0.15)) (justify left))
    )
    (property "License" "Apache-2.0" (at 251.46 81.915 0)
      (effects (font (size 1.27 1.27) (thickness 0.15)) (justify left bottom) hide)
    )
    (property "Author" "Antmicro" (at 254 81.915 0)
      (effects (font (size 1.27 1.27) (thickness 0.15)) (justify left bottom) hide)
    )
    (property "Tolerance" "1%" (at 236.22 81.915 0)
      (effects (font (size 1.27 1.27)) (justify left bottom) hide)
    )
    (pin "1")
    (pin "2")
    (instances
      (project "kria-k26-devboard"
        (path ""
          (reference "R17") (unit 1)
        )
      )
    )
  )

  (symbol (lib_id "kria-k26-devboard:GND") (at 226.06 113.03 0) (unit 1)
    (in_bom yes) (on_board yes) (dnp no) (fields_autoplaced)
    (property "Reference" "#PWR031" (at 226.06 119.38 0)
      (effects (font (size 1.27 1.27)) hide)
    )
    (property "Value" "GND" (at 226.06 118.11 0)
      (effects (font (size 1.27 1.27)))
    )
    (property "Footprint" "" (at 234.95 120.65 0)
      (effects (font (size 1.27 1.27) (thickness 0.15)) (justify left bottom) hide)
    )
    (property "Datasheet" "" (at 234.95 125.73 0)
      (effects (font (size 1.27 1.27) (thickness 0.15)) (justify left bottom) hide)
    )
    (property "Author" "Antmicro" (at 234.95 120.65 0)
      (effects (font (size 1.27 1.27) (thickness 0.15)) (justify left bottom) hide)
    )
    (property "License" "Apache-2.0" (at 234.95 123.19 0)
      (effects (font (size 1.27 1.27) (thickness 0.15)) (justify left bottom) hide)
    )
    (pin "1")
    (instances
      (project "kria-k26-devboard"
        (path ""
          (reference "#PWR031") (unit 1)
        )
      )
    )
  )

  (symbol (lib_id "kria-k26-devboard:C_470n_0402") (at 234.315 88.265 270) (unit 1)
    (in_bom yes) (on_board yes) (dnp no) (fields_autoplaced)
    (property "Reference" "C17" (at 237.49 89.5413 90)
      (effects (font (size 1.524 1.524)) (justify left))
    )
    (property "Value" "C_470n_0402" (at 224.155 108.585 0)
      (effects (font (size 1.27 1.27) (thickness 0.15)) (justify left bottom) hide)
    )
    (property "Footprint" "kria-k26-devboard-footprints:C_0402_1005Metric" (at 221.615 108.585 0)
      (effects (font (size 1.27 1.27) (thickness 0.15)) (justify left bottom) hide)
    )
    (property "Datasheet" " " (at 219.075 108.585 0)
      (effects (font (size 1.27 1.27) (thickness 0.15)) (justify left bottom) hide)
    )
    (property "Manufacturer" "TDK" (at 213.995 108.585 0)
      (effects (font (size 1.27 1.27) (thickness 0.15)) (justify left bottom) hide)
    )
    (property "MPN" "C1005X5R1E474M050BB" (at 216.535 108.585 0)
      (effects (font (size 1.27 1.27) (thickness 0.15)) (justify left bottom) hide)
    )
    (property "Val" "470n" (at 237.49 92.7162 90)
      (effects (font (size 1.27 1.27) (thickness 0.15)) (justify left))
    )
    (property "License" "Apache-2.0" (at 211.455 108.585 0)
      (effects (font (size 1.27 1.27) (thickness 0.15)) (justify left bottom) hide)
    )
    (property "Author" "Antmicro" (at 208.915 108.585 0)
      (effects (font (size 1.27 1.27) (thickness 0.15)) (justify left bottom) hide)
    )
    (property "Voltage" "" (at 206.375 108.585 0)
      (effects (font (size 1.27 1.27)) (justify left bottom) hide)
    )
    (property "Dielectric" "" (at 203.835 108.585 0)
      (effects (font (size 1.27 1.27)) (justify left bottom) hide)
    )
    (pin "1")
    (pin "2")
    (instances
      (project "kria-k26-devboard"
        (path ""
          (reference "C17") (unit 1)
        )
      )
    )
  )

  (symbol (lib_id "kria-k26-devboard:R_10k_0402") (at 226.06 88.265 270) (unit 1)
    (in_bom yes) (on_board yes) (dnp no) (fields_autoplaced)
    (property "Reference" "R16" (at 223.52 89.535 90)
      (effects (font (size 1.524 1.524)) (justify right))
    )
    (property "Value" "R_10k_0402" (at 213.36 108.585 0)
      (effects (font (size 1.27 1.27) (thickness 0.15)) (justify left bottom) hide)
    )
    (property "Footprint" "kria-k26-devboard-footprints:R_0402_1005Metric" (at 210.82 108.585 0)
      (effects (font (size 1.27 1.27) (thickness 0.15)) (justify left bottom) hide)
    )
    (property "Datasheet" "https://www.bourns.com/docs/product-datasheets/cr.pdf" (at 208.28 108.585 0)
      (effects (font (size 1.27 1.27) (thickness 0.15)) (justify left bottom) hide)
    )
    (property "Manufacturer" "Bourns" (at 203.2 108.585 0)
      (effects (font (size 1.27 1.27) (thickness 0.15)) (justify left bottom) hide)
    )
    (property "MPN" "CR0402-FX-1002GLF" (at 205.74 108.585 0)
      (effects (font (size 1.27 1.27) (thickness 0.15)) (justify left bottom) hide)
    )
    (property "Val" "10k" (at 223.52 92.7099 90)
      (effects (font (size 1.27 1.27) (thickness 0.15)) (justify right))
    )
    (property "License" "Apache-2.0" (at 200.66 108.585 0)
      (effects (font (size 1.27 1.27) (thickness 0.15)) (justify left bottom) hide)
    )
    (property "Author" "Antmicro" (at 198.12 108.585 0)
      (effects (font (size 1.27 1.27) (thickness 0.15)) (justify left bottom) hide)
    )
    (property "Tolerance" "1%" (at 215.9 108.585 0)
      (effects (font (size 1.27 1.27)) (justify left bottom) hide)
    )
    (pin "1")
    (pin "2")
    (instances
      (project "kria-k26-devboard"
        (path ""
          (reference "R16") (unit 1)
        )
      )
    )
  )

  (symbol (lib_id "kria-k26-devboard:AO3401A") (at 241.935 95.25 0) (mirror x) (unit 1)
    (in_bom yes) (on_board yes) (dnp no) (fields_autoplaced)
    (property "Reference" "Q2" (at 253.365 96.52 0)
      (effects (font (size 1.524 1.524)) (justify left))
    )
    (property "Value" "AO3401A" (at 253.365 99.6949 0)
      (effects (font (size 1.27 1.27) (thickness 0.15)) (justify left))
    )
    (property "Footprint" "kria-k26-devboard-footprints:SOT-23-3" (at 264.795 83.82 0)
      (effects (font (size 1.27 1.27) (thickness 0.15)) (justify left bottom) hide)
    )
    (property "Datasheet" "http://aosmd.com/res/data_sheets/AO3401A.pdf" (at 264.795 81.28 0)
      (effects (font (size 1.27 1.27) (thickness 0.15)) (justify left bottom) hide)
    )
    (property "MPN" "AO3401A" (at 264.795 78.74 0)
      (effects (font (size 1.27 1.27) (thickness 0.15)) (justify left bottom) hide)
    )
    (property "Manufacturer" "Alpha & Omega Semiconductor Inc." (at 264.795 76.2 0)
      (effects (font (size 1.27 1.27) (thickness 0.15)) (justify left bottom) hide)
    )
    (property "Author" "Antmicro" (at 264.795 73.66 0)
      (effects (font (size 1.27 1.27) (thickness 0.15)) (justify left bottom) hide)
    )
    (property "License" "Apache-2.0" (at 264.795 71.12 0)
      (effects (font (size 1.27 1.27) (thickness 0.15)) (justify left bottom) hide)
    )
    (pin "1")
    (pin "2")
    (pin "3")
    (instances
      (project "kria-k26-devboard"
        (path ""
          (reference "Q2") (unit 1)
        )
      )
    )
  )

  (symbol (lib_id "kria-k26-devboard:BSS123") (at 218.44 110.49 0) (unit 1)
    (in_bom yes) (on_board yes) (dnp no) (fields_autoplaced)
    (property "Reference" "Q1" (at 229.87 106.68 0)
      (effects (font (size 1.524 1.524)) (justify left))
    )
    (property "Value" "BSS123" (at 229.87 109.8549 0)
      (effects (font (size 1.27 1.27) (thickness 0.15)) (justify left))
    )
    (property "Footprint" "kria-k26-devboard-footprints:SOT-23-3" (at 241.3 121.92 0)
      (effects (font (size 1.27 1.27) (thickness 0.15)) (justify left bottom) hide)
    )
    (property "Datasheet" "https://www.onsemi.com/pub/Collateral/BSS123-D.PDF" (at 241.3 124.46 0)
      (effects (font (size 1.27 1.27) (thickness 0.15)) (justify left bottom) hide)
    )
    (property "MPN" "BSS123" (at 241.3 127 0)
      (effects (font (size 1.27 1.27) (thickness 0.15)) (justify left bottom) hide)
    )
    (property "Manufacturer" "ON Semiconductor" (at 241.3 129.54 0)
      (effects (font (size 1.27 1.27) (thickness 0.15)) (justify left bottom) hide)
    )
    (property "Author" "Antmicro" (at 241.3 132.08 0)
      (effects (font (size 1.27 1.27) (thickness 0.15)) (justify left bottom) hide)
    )
    (property "License" "Apache-2.0" (at 241.3 134.62 0)
      (effects (font (size 1.27 1.27) (thickness 0.15)) (justify left bottom) hide)
    )
    (pin "1")
    (pin "2")
    (pin "3")
    (instances
      (project "kria-k26-devboard"
        (path ""
          (reference "Q1") (unit 1)
        )
      )
    )
  )

  (symbol (lib_id "kria-k26-devboard:C_470n_0402") (at 234.315 97.155 270) (unit 1)
    (in_bom yes) (on_board yes) (dnp no) (fields_autoplaced)
    (property "Reference" "C18" (at 236.855 98.4313 90)
      (effects (font (size 1.524 1.524)) (justify left))
    )
    (property "Value" "C_470n_0402" (at 224.155 117.475 0)
      (effects (font (size 1.27 1.27) (thickness 0.15)) (justify left bottom) hide)
    )
    (property "Footprint" "kria-k26-devboard-footprints:C_0402_1005Metric" (at 221.615 117.475 0)
      (effects (font (size 1.27 1.27) (thickness 0.15)) (justify left bottom) hide)
    )
    (property "Datasheet" " " (at 219.075 117.475 0)
      (effects (font (size 1.27 1.27) (thickness 0.15)) (justify left bottom) hide)
    )
    (property "Manufacturer" "TDK" (at 213.995 117.475 0)
      (effects (font (size 1.27 1.27) (thickness 0.15)) (justify left bottom) hide)
    )
    (property "MPN" "C1005X5R1E474M050BB" (at 216.535 117.475 0)
      (effects (font (size 1.27 1.27) (thickness 0.15)) (justify left bottom) hide)
    )
    (property "Val" "470n" (at 236.855 101.6062 90)
      (effects (font (size 1.27 1.27) (thickness 0.15)) (justify left))
    )
    (property "License" "Apache-2.0" (at 211.455 117.475 0)
      (effects (font (size 1.27 1.27) (thickness 0.15)) (justify left bottom) hide)
    )
    (property "Author" "Antmicro" (at 208.915 117.475 0)
      (effects (font (size 1.27 1.27) (thickness 0.15)) (justify left bottom) hide)
    )
    (property "Voltage" "" (at 206.375 117.475 0)
      (effects (font (size 1.27 1.27)) (justify left bottom) hide)
    )
    (property "Dielectric" "" (at 203.835 117.475 0)
      (effects (font (size 1.27 1.27)) (justify left bottom) hide)
    )
    (pin "1")
    (pin "2")
    (instances
      (project "kria-k26-devboard"
        (path ""
          (reference "C18") (unit 1)
        )
      )
    )
  )

  (symbol (lib_id "kria-k26-devboard:C_100n_0402") (at 179.07 191.135 270) (unit 1)
    (in_bom yes) (on_board yes) (dnp no) (fields_autoplaced)
    (property "Reference" "C14" (at 181.61 192.4113 90)
      (effects (font (size 1.524 1.524)) (justify left))
    )
    (property "Value" "C_100n_0402" (at 168.91 211.455 0)
      (effects (font (size 1.27 1.27) (thickness 0.15)) (justify left bottom) hide)
    )
    (property "Footprint" "kria-k26-devboard-footprints:C_0402_1005Metric" (at 166.37 211.455 0)
      (effects (font (size 1.27 1.27) (thickness 0.15)) (justify left bottom) hide)
    )
    (property "Datasheet" "https://search.murata.co.jp/Ceramy/image/img/A01X/G101/ENG/GRM155R61H104KE14-01.pdf" (at 163.83 211.455 0)
      (effects (font (size 1.27 1.27) (thickness 0.15)) (justify left bottom) hide)
    )
    (property "Manufacturer" "Murata" (at 158.75 211.455 0)
      (effects (font (size 1.27 1.27) (thickness 0.15)) (justify left bottom) hide)
    )
    (property "MPN" "GRM155R61H104KE14D" (at 161.29 211.455 0)
      (effects (font (size 1.27 1.27) (thickness 0.15)) (justify left bottom) hide)
    )
    (property "Val" "100n" (at 181.61 195.5862 90)
      (effects (font (size 1.27 1.27) (thickness 0.15)) (justify left))
    )
    (property "License" "Apache-2.0" (at 156.21 211.455 0)
      (effects (font (size 1.27 1.27) (thickness 0.15)) (justify left bottom) hide)
    )
    (property "Author" "Antmicro" (at 153.67 211.455 0)
      (effects (font (size 1.27 1.27) (thickness 0.15)) (justify left bottom) hide)
    )
    (property "Voltage" "50V" (at 151.13 211.455 0)
      (effects (font (size 1.27 1.27)) (justify left bottom) hide)
    )
    (property "Dielectric" "X5R" (at 148.59 211.455 0)
      (effects (font (size 1.27 1.27)) (justify left bottom) hide)
    )
    (pin "1")
    (pin "2")
    (instances
      (project "kria-k26-devboard"
        (path ""
          (reference "C14") (unit 1)
        )
      )
    )
  )

  (symbol (lib_id "kria-k26-devboard:GND") (at 179.07 196.215 0) (unit 1)
    (in_bom yes) (on_board yes) (dnp no) (fields_autoplaced)
    (property "Reference" "#PWR026" (at 179.07 202.565 0)
      (effects (font (size 1.27 1.27)) hide)
    )
    (property "Value" "GND" (at 179.07 201.295 0)
      (effects (font (size 1.27 1.27)))
    )
    (property "Footprint" "" (at 187.96 203.835 0)
      (effects (font (size 1.27 1.27) (thickness 0.15)) (justify left bottom) hide)
    )
    (property "Datasheet" "" (at 187.96 208.915 0)
      (effects (font (size 1.27 1.27) (thickness 0.15)) (justify left bottom) hide)
    )
    (property "Author" "Antmicro" (at 187.96 203.835 0)
      (effects (font (size 1.27 1.27) (thickness 0.15)) (justify left bottom) hide)
    )
    (property "License" "Apache-2.0" (at 187.96 206.375 0)
      (effects (font (size 1.27 1.27) (thickness 0.15)) (justify left bottom) hide)
    )
    (pin "1")
    (instances
      (project "kria-k26-devboard"
        (path ""
          (reference "#PWR026") (unit 1)
        )
      )
    )
  )

  (symbol (lib_id "kria-k26-devboard:C_100n_0402") (at 198.12 191.135 270) (unit 1)
    (in_bom yes) (on_board yes) (dnp no) (fields_autoplaced)
    (property "Reference" "C16" (at 200.66 192.4113 90)
      (effects (font (size 1.524 1.524)) (justify left))
    )
    (property "Value" "C_100n_0402" (at 187.96 211.455 0)
      (effects (font (size 1.27 1.27) (thickness 0.15)) (justify left bottom) hide)
    )
    (property "Footprint" "kria-k26-devboard-footprints:C_0402_1005Metric" (at 185.42 211.455 0)
      (effects (font (size 1.27 1.27) (thickness 0.15)) (justify left bottom) hide)
    )
    (property "Datasheet" "https://search.murata.co.jp/Ceramy/image/img/A01X/G101/ENG/GRM155R61H104KE14-01.pdf" (at 182.88 211.455 0)
      (effects (font (size 1.27 1.27) (thickness 0.15)) (justify left bottom) hide)
    )
    (property "Manufacturer" "Murata" (at 177.8 211.455 0)
      (effects (font (size 1.27 1.27) (thickness 0.15)) (justify left bottom) hide)
    )
    (property "MPN" "GRM155R61H104KE14D" (at 180.34 211.455 0)
      (effects (font (size 1.27 1.27) (thickness 0.15)) (justify left bottom) hide)
    )
    (property "Val" "100n" (at 200.66 195.5862 90)
      (effects (font (size 1.27 1.27) (thickness 0.15)) (justify left))
    )
    (property "License" "Apache-2.0" (at 175.26 211.455 0)
      (effects (font (size 1.27 1.27) (thickness 0.15)) (justify left bottom) hide)
    )
    (property "Author" "Antmicro" (at 172.72 211.455 0)
      (effects (font (size 1.27 1.27) (thickness 0.15)) (justify left bottom) hide)
    )
    (property "Voltage" "50V" (at 170.18 211.455 0)
      (effects (font (size 1.27 1.27)) (justify left bottom) hide)
    )
    (property "Dielectric" "X5R" (at 167.64 211.455 0)
      (effects (font (size 1.27 1.27)) (justify left bottom) hide)
    )
    (pin "1")
    (pin "2")
    (instances
      (project "kria-k26-devboard"
        (path ""
          (reference "C16") (unit 1)
        )
      )
    )
  )

  (symbol (lib_id "kria-k26-devboard:GND") (at 198.12 196.215 0) (unit 1)
    (in_bom yes) (on_board yes) (dnp no) (fields_autoplaced)
    (property "Reference" "#PWR030" (at 198.12 202.565 0)
      (effects (font (size 1.27 1.27)) hide)
    )
    (property "Value" "GND" (at 198.12 201.295 0)
      (effects (font (size 1.27 1.27)))
    )
    (property "Footprint" "" (at 207.01 203.835 0)
      (effects (font (size 1.27 1.27) (thickness 0.15)) (justify left bottom) hide)
    )
    (property "Datasheet" "" (at 207.01 208.915 0)
      (effects (font (size 1.27 1.27) (thickness 0.15)) (justify left bottom) hide)
    )
    (property "Author" "Antmicro" (at 207.01 203.835 0)
      (effects (font (size 1.27 1.27) (thickness 0.15)) (justify left bottom) hide)
    )
    (property "License" "Apache-2.0" (at 207.01 206.375 0)
      (effects (font (size 1.27 1.27) (thickness 0.15)) (justify left bottom) hide)
    )
    (pin "1")
    (instances
      (project "kria-k26-devboard"
        (path ""
          (reference "#PWR030") (unit 1)
        )
      )
    )
  )

  (symbol (lib_id "kria-k26-devboard:GND") (at 263.525 170.815 0) (unit 1)
    (in_bom yes) (on_board yes) (dnp no) (fields_autoplaced)
    (property "Reference" "#PWR0290" (at 263.525 177.165 0)
      (effects (font (size 1.27 1.27)) hide)
    )
    (property "Value" "GND" (at 263.525 175.895 0)
      (effects (font (size 1.27 1.27)))
    )
    (property "Footprint" "" (at 272.415 178.435 0)
      (effects (font (size 1.27 1.27) (thickness 0.15)) (justify left bottom) hide)
    )
    (property "Datasheet" "" (at 272.415 183.515 0)
      (effects (font (size 1.27 1.27) (thickness 0.15)) (justify left bottom) hide)
    )
    (property "Author" "Antmicro" (at 272.415 178.435 0)
      (effects (font (size 1.27 1.27) (thickness 0.15)) (justify left bottom) hide)
    )
    (property "License" "Apache-2.0" (at 272.415 180.975 0)
      (effects (font (size 1.27 1.27) (thickness 0.15)) (justify left bottom) hide)
    )
    (pin "1")
    (instances
      (project "kria-k26-devboard"
        (path ""
          (reference "#PWR0290") (unit 1)
        )
      )
    )
  )

  (symbol (lib_id "kria-k26-devboard:GND") (at 267.97 113.03 0) (unit 1)
    (in_bom yes) (on_board yes) (dnp no) (fields_autoplaced)
    (property "Reference" "#PWR0289" (at 267.97 119.38 0)
      (effects (font (size 1.27 1.27)) hide)
    )
    (property "Value" "GND" (at 267.97 118.11 0)
      (effects (font (size 1.27 1.27)))
    )
    (property "Footprint" "" (at 276.86 120.65 0)
      (effects (font (size 1.27 1.27) (thickness 0.15)) (justify left bottom) hide)
    )
    (property "Datasheet" "" (at 276.86 125.73 0)
      (effects (font (size 1.27 1.27) (thickness 0.15)) (justify left bottom) hide)
    )
    (property "Author" "Antmicro" (at 276.86 120.65 0)
      (effects (font (size 1.27 1.27) (thickness 0.15)) (justify left bottom) hide)
    )
    (property "License" "Apache-2.0" (at 276.86 123.19 0)
      (effects (font (size 1.27 1.27) (thickness 0.15)) (justify left bottom) hide)
    )
    (pin "1")
    (instances
      (project "kria-k26-devboard"
        (path ""
          (reference "#PWR0289") (unit 1)
        )
      )
    )
  )

  (symbol (lib_id "kria-k26-devboard:R_10k_0402") (at 184.785 108.585 90) (unit 1)
    (in_bom yes) (on_board yes) (dnp no) (fields_autoplaced)
    (property "Reference" "R168" (at 186.69 104.775 90)
      (effects (font (size 1.524 1.524)) (justify right))
    )
    (property "Value" "R_10k_0402" (at 197.485 88.265 0)
      (effects (font (size 1.27 1.27) (thickness 0.15)) (justify left bottom) hide)
    )
    (property "Footprint" "kria-k26-devboard-footprints:R_0402_1005Metric" (at 200.025 88.265 0)
      (effects (font (size 1.27 1.27) (thickness 0.15)) (justify left bottom) hide)
    )
    (property "Datasheet" "https://www.bourns.com/docs/product-datasheets/cr.pdf" (at 202.565 88.265 0)
      (effects (font (size 1.27 1.27) (thickness 0.15)) (justify left bottom) hide)
    )
    (property "Manufacturer" "Bourns" (at 207.645 88.265 0)
      (effects (font (size 1.27 1.27) (thickness 0.15)) (justify left bottom) hide)
    )
    (property "MPN" "CR0402-FX-1002GLF" (at 205.105 88.265 0)
      (effects (font (size 1.27 1.27) (thickness 0.15)) (justify left bottom) hide)
    )
    (property "Val" "10k" (at 186.69 107.9499 90)
      (effects (font (size 1.27 1.27) (thickness 0.15)) (justify right))
    )
    (property "License" "Apache-2.0" (at 210.185 88.265 0)
      (effects (font (size 1.27 1.27) (thickness 0.15)) (justify left bottom) hide)
    )
    (property "Author" "Antmicro" (at 212.725 88.265 0)
      (effects (font (size 1.27 1.27) (thickness 0.15)) (justify left bottom) hide)
    )
    (property "Tolerance" "1%" (at 194.945 88.265 0)
      (effects (font (size 1.27 1.27)) (justify left bottom) hide)
    )
    (pin "1")
    (pin "2")
    (instances
      (project "kria-k26-devboard"
        (path ""
          (reference "R168") (unit 1)
        )
      )
    )
  )

  (symbol (lib_id "kria-k26-devboard:GND") (at 237.49 170.815 0) (mirror y) (unit 1)
    (in_bom yes) (on_board yes) (dnp no) (fields_autoplaced)
    (property "Reference" "#PWR0291" (at 237.49 177.165 0)
      (effects (font (size 1.27 1.27)) hide)
    )
    (property "Value" "GND" (at 237.49 175.895 0)
      (effects (font (size 1.27 1.27)))
    )
    (property "Footprint" "" (at 228.6 178.435 0)
      (effects (font (size 1.27 1.27) (thickness 0.15)) (justify left bottom) hide)
    )
    (property "Datasheet" "" (at 228.6 183.515 0)
      (effects (font (size 1.27 1.27) (thickness 0.15)) (justify left bottom) hide)
    )
    (property "Author" "Antmicro" (at 228.6 178.435 0)
      (effects (font (size 1.27 1.27) (thickness 0.15)) (justify left bottom) hide)
    )
    (property "License" "Apache-2.0" (at 228.6 180.975 0)
      (effects (font (size 1.27 1.27) (thickness 0.15)) (justify left bottom) hide)
    )
    (pin "1")
    (instances
      (project "kria-k26-devboard"
        (path ""
          (reference "#PWR0291") (unit 1)
        )
      )
    )
  )

  (symbol (lib_id "kria-k26-devboard:R_4x33R_0201_array") (at 160.655 165.1 0) (mirror x) (unit 1)
    (in_bom yes) (on_board yes) (dnp no)
    (property "Reference" "R15" (at 165.735 154.94 0)
      (effects (font (size 1.524 1.524)))
    )
    (property "Value" "R_4x33R_0201_array" (at 165.735 151.13 0)
      (effects (font (size 1.27 1.27) (thickness 0.15)) hide)
    )
    (property "Footprint" "kria-k26-devboard-footprints:R_Array_4x0201_Panasonic_EXB18V" (at 187.325 154.305 0)
      (effects (font (size 1.27 1.27) (thickness 0.15)) (justify left bottom) hide)
    )
    (property "Datasheet" "http://industrial.panasonic.com/cdbs/www-data/pdf/AOC0000/AOC0000C14.pdf" (at 187.325 151.765 0)
      (effects (font (size 1.27 1.27) (thickness 0.15)) (justify left bottom) hide)
    )
    (property "MPN" "EXB-18V330JX" (at 187.325 149.225 0)
      (effects (font (size 1.27 1.27) (thickness 0.15)) (justify left bottom) hide)
    )
    (property "Manufacturer" "Panasonic" (at 187.325 146.685 0)
      (effects (font (size 1.27 1.27) (thickness 0.15)) (justify left bottom) hide)
    )
    (property "Author" "Antmicro" (at 187.325 144.145 0)
      (effects (font (size 1.27 1.27) (thickness 0.15)) (justify left bottom) hide)
    )
    (property "License" "Apache-2.0" (at 187.325 141.605 0)
      (effects (font (size 1.27 1.27) (thickness 0.15)) (justify left bottom) hide)
    )
    (property "Val" "R_4x33R_0201" (at 165.735 167.64 0)
      (effects (font (size 1.27 1.27)))
    )
    (pin "1")
    (pin "2")
    (pin "3")
    (pin "4")
    (pin "5")
    (pin "6")
    (pin "7")
    (pin "8")
    (instances
      (project "kria-k26-devboard"
        (path ""
          (reference "R15") (unit 1)
        )
      )
    )
  )

  (symbol (lib_id "kria-k26-devboard:TP_0.75mm_SMD") (at 186.69 110.49 0) (unit 1)
    (in_bom yes) (on_board yes) (dnp no)
    (property "Reference" "TP60" (at 193.675 110.49 0)
      (effects (font (size 1.27 1.27)))
    )
    (property "Value" "TP_0.75mm_SMD" (at 204.47 118.11 0)
      (effects (font (size 1.27 1.27) (thickness 0.15)) (justify left bottom) hide)
    )
    (property "Footprint" "kria-k26-devboard-footprints:TP_SMD_0.75mm" (at 204.47 120.65 0)
      (effects (font (size 1.27 1.27) (thickness 0.15)) (justify left bottom) hide)
    )
    (property "Datasheet" "" (at 204.47 123.19 0)
      (effects (font (size 1.27 1.27) (thickness 0.15)) (justify left bottom) hide)
    )
    (property "MPN" "" (at 204.47 125.73 0)
      (effects (font (size 1.27 1.27) (thickness 0.15)) (justify left bottom) hide)
    )
    (property "Manufacturer" "" (at 204.47 128.27 0)
      (effects (font (size 1.27 1.27) (thickness 0.15)) (justify left bottom) hide)
    )
    (property "Author" "Antmicro" (at 204.47 130.81 0)
      (effects (font (size 1.27 1.27) (thickness 0.15)) (justify left bottom) hide)
    )
    (property "License" "Apache-2.0" (at 204.47 133.35 0)
      (effects (font (size 1.27 1.27) (thickness 0.15)) (justify left bottom) hide)
    )
    (pin "1")
    (instances
      (project "kria-k26-devboard"
        (path ""
          (reference "TP60") (unit 1)
        )
      )
    )
  )
)
